(kicad_pcb
	(version 20260206)
	(generator "pcbnew")
	(generator_version "10.0")
	(general
		(thickness 1.6)
		(legacy_teardrops no)
	)
	(paper "A4")
	(title_block
		(title "Bryce Canyon_Front Panel_16369-1_OCP.brd")
		(comment 1 "Bryce Canyon / footprints 29-35 of 154")
	)
	(layers
		(0 "F.Cu" signal "TOP")
		(4 "In1.Cu" signal "L2GND")
		(6 "In2.Cu" signal "L3VCC")
		(2 "B.Cu" signal "BOTTOM")
		(9 "F.Adhes" user "F.Adhesive")
		(11 "B.Adhes" user "B.Adhesive")
		(13 "F.Paste" user "Package Geometry/Pastemask Top")
		(15 "B.Paste" user "Package Geometry/Pastemask Bottom")
		(5 "F.SilkS" user "Ref Des/Silkscreen Top")
		(7 "B.SilkS" user "Ref Des/Silkscreen Bottom")
		(1 "F.Mask" user "Board Geometry/Soldermask Top")
		(3 "B.Mask" user "Board Geometry/Soldermask Bottom")
		(17 "Dwgs.User" user "User.Drawings")
		(19 "Cmts.User" user "User.Comments")
		(21 "Eco1.User" user "User.Eco1")
		(23 "Eco2.User" user "User.Eco2")
		(25 "Edge.Cuts" user "Board Geometry/Outline")
		(27 "Margin" user)
		(31 "F.CrtYd" user "Package Geometry/Place Bound Top")
		(29 "B.CrtYd" user "Package Geometry/Place Bound Bottom")
		(35 "F.Fab" user "Ref Des/Assembly Top")
		(33 "B.Fab" user "Ref Des/Assembly Bottom")
	)
	(footprint ""
		(layer "F.Cu")
		(at 10.16 -30.099 90)
		(property "Reference" "R50"
			(at 0 0 90)
			(layer "F.SilkS")
			(hide yes)
			(effects
				(font
					(size 1.27 1.27)
				)
			)
		)
		(property "Value" "4K7R2F-GP"
			(at 0.064008 -4.679696 90)
			(unlocked yes)
			(layer "F.Fab")
			(hide yes)
			(effects
				(font
					(size 2.54 2.54)
					(thickness 0.381)
				)
			)
		)
		(property "Device Type" "R402H16"
			(at 0.064008 -6.203696 90)
			(unlocked yes)
			(layer "F.Fab")
			(hide yes)
			(effects
				(font
					(size 2.54 2.54)
					(thickness 0.381)
				)
			)
		)
		(duplicate_pad_numbers_are_jumpers no)
		(fp_line
			(start 0.508 -0.9398)
			(end -0.508 -0.9398)
			(stroke
				(width 0.1524)
				(type default)
			)
			(layer "F.SilkS")
		)
		(fp_line
			(start -0.508 -0.9398)
			(end -0.508 0.9398)
			(stroke
				(width 0.1524)
				(type default)
			)
			(layer "F.SilkS")
		)
		(fp_rect
			(start -0.508 0.9398)
			(end 0.508 -0.9398)
			(stroke
				(width 0)
				(type default)
			)
			(fill no)
			(layer "F.CrtYd")
		)
		(fp_rect
			(start -0.508 0.9398)
			(end 0.508 -0.9398)
			(stroke
				(width 0)
				(type default)
			)
			(fill no)
			(layer "F.Fab")
		)
		(pad "1" smd custom
			(at 0 -0.4445 90)
			(size 0.1397 0.1397)
			(layers "F.Cu" "F.Mask" "F.Paste")
			(net "RST_A_TS")
			(options
				(clearance outline)
				(anchor circle)
			)
			(primitives
				(gr_poly
					(pts
						(arc
							(start -0.1778 -0.2794)
							(mid -0.249642 -0.249642)
							(end -0.2794 -0.1778)
						)
						(arc
							(start -0.2794 0.1778)
							(mid -0.249642 0.249642)
							(end -0.1778 0.2794)
						)
						(arc
							(start 0.1778 0.2794)
							(mid 0.249642 0.249642)
							(end 0.2794 0.1778)
						)
						(arc
							(start 0.2794 -0.1778)
							(mid 0.249642 -0.249642)
							(end 0.1778 -0.2794)
						)
					)
					(width 0)
					(fill yes)
				)
			)
		)
		(pad "2" smd custom
			(at 0 0.4445 90)
			(size 0.1397 0.1397)
			(layers "F.Cu" "F.Mask" "F.Paste")
			(net "GND")
			(options
				(clearance outline)
				(anchor circle)
			)
			(primitives
				(gr_poly
					(pts
						(arc
							(start -0.1778 -0.2794)
							(mid -0.249642 -0.249642)
							(end -0.2794 -0.1778)
						)
						(arc
							(start -0.2794 0.1778)
							(mid -0.249642 0.249642)
							(end -0.1778 0.2794)
						)
						(arc
							(start 0.1778 0.2794)
							(mid 0.249642 0.249642)
							(end 0.2794 0.1778)
						)
						(arc
							(start 0.2794 -0.1778)
							(mid 0.249642 -0.249642)
							(end 0.1778 -0.2794)
						)
					)
					(width 0)
					(fill yes)
				)
			)
		)
	)
	(footprint ""
		(layer "F.Cu")
		(at 48.527716 -72.650096 180)
		(property "Reference" "C8"
			(at 0 0 180)
			(layer "F.SilkS")
			(hide yes)
			(effects
				(font
					(size 1.27 1.27)
				)
			)
		)
		(property "Value" "SC1U16V3KX-5GP"
			(at 0 -3.5052 180)
			(unlocked yes)
			(layer "F.Fab")
			(hide yes)
			(effects
				(font
					(size 2.54 2.54)
					(thickness 0.381)
				)
			)
		)
		(property "Device Type" "C603H36"
			(at 0 -5.0292 180)
			(unlocked yes)
			(layer "F.Fab")
			(hide yes)
			(effects
				(font
					(size 2.54 2.54)
					(thickness 0.381)
				)
			)
		)
		(duplicate_pad_numbers_are_jumpers no)
		(fp_line
			(start 0.508 0)
			(end -0.508 0)
			(stroke
				(width 0.2032)
				(type default)
			)
			(layer "F.SilkS")
		)
		(fp_rect
			(start -0.5842 1.3335)
			(end 0.5842 -1.3335)
			(stroke
				(width 0)
				(type default)
			)
			(fill no)
			(layer "F.CrtYd")
		)
		(fp_rect
			(start -0.5842 1.3335)
			(end 0.5842 -1.3335)
			(stroke
				(width 0)
				(type default)
			)
			(fill no)
			(layer "F.Fab")
		)
		(pad "1" smd custom
			(at 0 -0.762 180)
			(size 0.2159 0.2159)
			(layers "F.Cu" "F.Mask" "F.Paste")
			(net "P5V_USB_B")
			(options
				(clearance outline)
				(anchor circle)
			)
			(primitives
				(gr_poly
					(pts
						(arc
							(start -0.3302 -0.4318)
							(mid -0.402042 -0.402042)
							(end -0.4318 -0.3302)
						)
						(arc
							(start -0.4318 0.3302)
							(mid -0.402042 0.402042)
							(end -0.3302 0.4318)
						)
						(arc
							(start 0.3302 0.4318)
							(mid 0.402042 0.402042)
							(end 0.4318 0.3302)
						)
						(arc
							(start 0.4318 -0.3302)
							(mid 0.402042 -0.402042)
							(end 0.3302 -0.4318)
						)
					)
					(width 0)
					(fill yes)
				)
			)
		)
		(pad "2" smd custom
			(at 0 0.762 180)
			(size 0.2159 0.2159)
			(layers "F.Cu" "F.Mask" "F.Paste")
			(net "GND")
			(options
				(clearance outline)
				(anchor circle)
			)
			(primitives
				(gr_poly
					(pts
						(arc
							(start -0.3302 -0.4318)
							(mid -0.402042 -0.402042)
							(end -0.4318 -0.3302)
						)
						(arc
							(start -0.4318 0.3302)
							(mid -0.402042 0.402042)
							(end -0.3302 0.4318)
						)
						(arc
							(start 0.3302 0.4318)
							(mid 0.402042 0.402042)
							(end 0.4318 0.3302)
						)
						(arc
							(start 0.4318 -0.3302)
							(mid 0.402042 -0.402042)
							(end 0.3302 -0.4318)
						)
					)
					(width 0)
					(fill yes)
				)
			)
		)
	)
	(footprint ""
		(layer "F.Cu")
		(at 19.6596 -11.938 90)
		(property "Reference" "R3"
			(at 0 0 90)
			(layer "F.SilkS")
			(hide yes)
			(effects
				(font
					(size 1.27 1.27)
				)
			)
		)
		(property "Value" "0R2J-2-GP"
			(at 0.064008 -4.679696 90)
			(unlocked yes)
			(layer "F.Fab")
			(hide yes)
			(effects
				(font
					(size 2.54 2.54)
					(thickness 0.381)
				)
			)
		)
		(property "Device Type" "R402H16"
			(at 0.064008 -6.203696 90)
			(unlocked yes)
			(layer "F.Fab")
			(hide yes)
			(effects
				(font
					(size 2.54 2.54)
					(thickness 0.381)
				)
			)
		)
		(duplicate_pad_numbers_are_jumpers no)
		(fp_line
			(start 0.508 -0.9398)
			(end -0.508 -0.9398)
			(stroke
				(width 0.1524)
				(type default)
			)
			(layer "F.SilkS")
		)
		(fp_line
			(start -0.508 -0.9398)
			(end -0.508 0.9398)
			(stroke
				(width 0.1524)
				(type default)
			)
			(layer "F.SilkS")
		)
		(fp_rect
			(start -0.508 0.9398)
			(end 0.508 -0.9398)
			(stroke
				(width 0)
				(type default)
			)
			(fill no)
			(layer "F.CrtYd")
		)
		(fp_rect
			(start -0.508 0.9398)
			(end 0.508 -0.9398)
			(stroke
				(width 0)
				(type default)
			)
			(fill no)
			(layer "F.Fab")
		)
		(pad "1" smd custom
			(at 0 -0.4445 90)
			(size 0.1397 0.1397)
			(layers "F.Cu" "F.Mask" "F.Paste")
			(net "UART_SEL_A_MUX_R")
			(options
				(clearance outline)
				(anchor circle)
			)
			(primitives
				(gr_poly
					(pts
						(arc
							(start -0.1778 -0.2794)
							(mid -0.249642 -0.249642)
							(end -0.2794 -0.1778)
						)
						(arc
							(start -0.2794 0.1778)
							(mid -0.249642 0.249642)
							(end -0.1778 0.2794)
						)
						(arc
							(start 0.1778 0.2794)
							(mid 0.249642 0.249642)
							(end 0.2794 0.1778)
						)
						(arc
							(start 0.2794 -0.1778)
							(mid 0.249642 -0.249642)
							(end 0.1778 -0.2794)
						)
					)
					(width 0)
					(fill yes)
				)
			)
		)
		(pad "2" smd custom
			(at 0 0.4445 90)
			(size 0.1397 0.1397)
			(layers "F.Cu" "F.Mask" "F.Paste")
			(net "GND")
			(options
				(clearance outline)
				(anchor circle)
			)
			(primitives
				(gr_poly
					(pts
						(arc
							(start -0.1778 -0.2794)
							(mid -0.249642 -0.249642)
							(end -0.2794 -0.1778)
						)
						(arc
							(start -0.2794 0.1778)
							(mid -0.249642 0.249642)
							(end -0.1778 0.2794)
						)
						(arc
							(start 0.1778 0.2794)
							(mid 0.249642 0.249642)
							(end 0.2794 0.1778)
						)
						(arc
							(start 0.2794 -0.1778)
							(mid 0.249642 -0.249642)
							(end 0.1778 -0.2794)
						)
					)
					(width 0)
					(fill yes)
				)
			)
		)
	)
	(footprint ""
		(layer "F.Cu")
		(at 19.203416 -20.845526 180)
		(property "Reference" "R67"
			(at 0 0 180)
			(layer "F.SilkS")
			(hide yes)
			(effects
				(font
					(size 1.27 1.27)
				)
			)
		)
		(property "Value" "4K7R2F-GP"
			(at 0.064008 -3.993896 180)
			(unlocked yes)
			(layer "F.Fab")
			(hide yes)
			(effects
				(font
					(size 1.016 1.016)
					(thickness 0.1524)
				)
			)
		)
		(property "Device Type" "R402H16"
			(at 0.064008 -5.517896 180)
			(unlocked yes)
			(layer "F.Fab")
			(hide yes)
			(effects
				(font
					(size 1.016 1.016)
					(thickness 0.1524)
				)
			)
		)
		(duplicate_pad_numbers_are_jumpers no)
		(fp_line
			(start 0.508 -0.9398)
			(end -0.508 -0.9398)
			(stroke
				(width 0.1524)
				(type default)
			)
			(layer "F.SilkS")
		)
		(fp_line
			(start -0.508 -0.9398)
			(end -0.508 0.9398)
			(stroke
				(width 0.1524)
				(type default)
			)
			(layer "F.SilkS")
		)
		(fp_rect
			(start -0.508 0.9398)
			(end 0.508 -0.9398)
			(stroke
				(width 0)
				(type default)
			)
			(fill no)
			(layer "F.CrtYd")
		)
		(fp_rect
			(start -0.508 0.9398)
			(end 0.508 -0.9398)
			(stroke
				(width 0)
				(type default)
			)
			(fill no)
			(layer "F.Fab")
		)
		(pad "1" smd custom
			(at 0 -0.4445 180)
			(size 0.1397 0.1397)
			(layers "F.Cu" "F.Mask" "F.Paste")
			(net "TCA9555_A_A2")
			(options
				(clearance outline)
				(anchor circle)
			)
			(primitives
				(gr_poly
					(pts
						(arc
							(start -0.1778 -0.2794)
							(mid -0.249642 -0.249642)
							(end -0.2794 -0.1778)
						)
						(arc
							(start -0.2794 0.1778)
							(mid -0.249642 0.249642)
							(end -0.1778 0.2794)
						)
						(arc
							(start 0.1778 0.2794)
							(mid 0.249642 0.249642)
							(end 0.2794 0.1778)
						)
						(arc
							(start 0.2794 -0.1778)
							(mid 0.249642 -0.249642)
							(end 0.1778 -0.2794)
						)
					)
					(width 0)
					(fill yes)
				)
			)
		)
		(pad "2" smd custom
			(at 0 0.4445 180)
			(size 0.1397 0.1397)
			(layers "F.Cu" "F.Mask" "F.Paste")
			(net "GND")
			(options
				(clearance outline)
				(anchor circle)
			)
			(primitives
				(gr_poly
					(pts
						(arc
							(start -0.1778 -0.2794)
							(mid -0.249642 -0.249642)
							(end -0.2794 -0.1778)
						)
						(arc
							(start -0.2794 0.1778)
							(mid -0.249642 0.249642)
							(end -0.1778 0.2794)
						)
						(arc
							(start 0.1778 0.2794)
							(mid 0.249642 0.249642)
							(end 0.2794 0.1778)
						)
						(arc
							(start 0.2794 -0.1778)
							(mid 0.249642 -0.249642)
							(end 0.1778 -0.2794)
						)
					)
					(width 0)
					(fill yes)
				)
			)
		)
	)
	(footprint ""
		(layer "F.Cu")
		(at 8.948674 -16.942816 90)
		(property "Reference" "R62"
			(at 0 0 90)
			(layer "F.SilkS")
			(hide yes)
			(effects
				(font
					(size 1.27 1.27)
				)
			)
		)
		(property "Value" "4K7R2F-GP"
			(at 0.064008 -3.993896 90)
			(unlocked yes)
			(layer "F.Fab")
			(hide yes)
			(effects
				(font
					(size 1.016 1.016)
					(thickness 0.1524)
				)
			)
		)
		(property "Device Type" "R402H16"
			(at 0.064008 -5.517896 90)
			(unlocked yes)
			(layer "F.Fab")
			(hide yes)
			(effects
				(font
					(size 1.016 1.016)
					(thickness 0.1524)
				)
			)
		)
		(duplicate_pad_numbers_are_jumpers no)
		(fp_line
			(start 0.508 -0.9398)
			(end -0.508 -0.9398)
			(stroke
				(width 0.1524)
				(type default)
			)
			(layer "F.SilkS")
		)
		(fp_line
			(start -0.508 -0.9398)
			(end -0.508 0.9398)
			(stroke
				(width 0.1524)
				(type default)
			)
			(layer "F.SilkS")
		)
		(fp_rect
			(start -0.508 0.9398)
			(end 0.508 -0.9398)
			(stroke
				(width 0)
				(type default)
			)
			(fill no)
			(layer "F.CrtYd")
		)
		(fp_rect
			(start -0.508 0.9398)
			(end 0.508 -0.9398)
			(stroke
				(width 0)
				(type default)
			)
			(fill no)
			(layer "F.Fab")
		)
		(pad "1" smd custom
			(at 0 -0.4445 90)
			(size 0.1397 0.1397)
			(layers "F.Cu" "F.Mask" "F.Paste")
			(net "P3V3_STBY_A")
			(options
				(clearance outline)
				(anchor circle)
			)
			(primitives
				(gr_poly
					(pts
						(arc
							(start -0.1778 -0.2794)
							(mid -0.249642 -0.249642)
							(end -0.2794 -0.1778)
						)
						(arc
							(start -0.2794 0.1778)
							(mid -0.249642 0.249642)
							(end -0.1778 0.2794)
						)
						(arc
							(start 0.1778 0.2794)
							(mid 0.249642 0.249642)
							(end 0.2794 0.1778)
						)
						(arc
							(start 0.2794 -0.1778)
							(mid 0.249642 -0.249642)
							(end 0.1778 -0.2794)
						)
					)
					(width 0)
					(fill yes)
				)
			)
		)
		(pad "2" smd custom
			(at 0 0.4445 90)
			(size 0.1397 0.1397)
			(layers "F.Cu" "F.Mask" "F.Paste")
			(net "TCA9555_A_A0")
			(options
				(clearance outline)
				(anchor circle)
			)
			(primitives
				(gr_poly
					(pts
						(arc
							(start -0.1778 -0.2794)
							(mid -0.249642 -0.249642)
							(end -0.2794 -0.1778)
						)
						(arc
							(start -0.2794 0.1778)
							(mid -0.249642 0.249642)
							(end -0.1778 0.2794)
						)
						(arc
							(start 0.1778 0.2794)
							(mid 0.249642 0.249642)
							(end 0.2794 0.1778)
						)
						(arc
							(start 0.2794 -0.1778)
							(mid 0.249642 -0.249642)
							(end 0.1778 -0.2794)
						)
					)
					(width 0)
					(fill yes)
				)
			)
		)
	)
	(footprint ""
		(layer "F.Cu")
		(at 20.219416 -20.845526)
		(property "Reference" "R64"
			(at 0 0 0)
			(layer "F.SilkS")
			(hide yes)
			(effects
				(font
					(size 1.27 1.27)
				)
			)
		)
		(property "Value" "4K7R2F-GP"
			(at 0.064008 -3.993896 0)
			(unlocked yes)
			(layer "F.Fab")
			(hide yes)
			(effects
				(font
					(size 1.016 1.016)
					(thickness 0.1524)
				)
			)
		)
		(property "Device Type" "R402H16"
			(at 0.064008 -5.517896 0)
			(unlocked yes)
			(layer "F.Fab")
			(hide yes)
			(effects
				(font
					(size 1.016 1.016)
					(thickness 0.1524)
				)
			)
		)
		(duplicate_pad_numbers_are_jumpers no)
		(fp_line
			(start -0.508 -0.9398)
			(end -0.508 0.9398)
			(stroke
				(width 0.1524)
				(type default)
			)
			(layer "F.SilkS")
		)
		(fp_line
			(start 0.508 -0.9398)
			(end -0.508 -0.9398)
			(stroke
				(width 0.1524)
				(type default)
			)
			(layer "F.SilkS")
		)
		(fp_rect
			(start -0.508 0.9398)
			(end 0.508 -0.9398)
			(stroke
				(width 0)
				(type default)
			)
			(fill no)
			(layer "F.CrtYd")
		)
		(fp_rect
			(start -0.508 0.9398)
			(end 0.508 -0.9398)
			(stroke
				(width 0)
				(type default)
			)
			(fill no)
			(layer "F.Fab")
		)
		(pad "1" smd custom
			(at 0 -0.4445)
			(size 0.1397 0.1397)
			(layers "F.Cu" "F.Mask" "F.Paste")
			(net "P3V3_STBY_A")
			(options
				(clearance outline)
				(anchor circle)
			)
			(primitives
				(gr_poly
					(pts
						(arc
							(start -0.1778 -0.2794)
							(mid -0.249642 -0.249642)
							(end -0.2794 -0.1778)
						)
						(arc
							(start -0.2794 0.1778)
							(mid -0.249642 0.249642)
							(end -0.1778 0.2794)
						)
						(arc
							(start 0.1778 0.2794)
							(mid 0.249642 0.249642)
							(end 0.2794 0.1778)
						)
						(arc
							(start 0.2794 -0.1778)
							(mid 0.249642 -0.249642)
							(end 0.1778 -0.2794)
						)
					)
					(width 0)
					(fill yes)
				)
			)
		)
		(pad "2" smd custom
			(at 0 0.4445)
			(size 0.1397 0.1397)
			(layers "F.Cu" "F.Mask" "F.Paste")
			(net "TCA9555_A_A2")
			(options
				(clearance outline)
				(anchor circle)
			)
			(primitives
				(gr_poly
					(pts
						(arc
							(start -0.1778 -0.2794)
							(mid -0.249642 -0.249642)
							(end -0.2794 -0.1778)
						)
						(arc
							(start -0.2794 0.1778)
							(mid -0.249642 0.249642)
							(end -0.1778 0.2794)
						)
						(arc
							(start 0.1778 0.2794)
							(mid 0.249642 0.249642)
							(end 0.2794 0.1778)
						)
						(arc
							(start 0.2794 -0.1778)
							(mid 0.249642 -0.249642)
							(end 0.1778 -0.2794)
						)
					)
					(width 0)
					(fill yes)
				)
			)
		)
	)
	(footprint ""
		(layer "F.Cu")
		(at 54.74208 -36.449)
		(property "Reference" "C13"
			(at 0 0 0)
			(layer "F.SilkS")
			(hide yes)
			(effects
				(font
					(size 1.27 1.27)
				)
			)
		)
		(property "Value" "SC1U16V3KX-5GP"
			(at 0 -3.5052 0)
			(unlocked yes)
			(layer "F.Fab")
			(hide yes)
			(effects
				(font
					(size 2.54 2.54)
					(thickness 0.381)
				)
			)
		)
		(property "Device Type" "C603H36"
			(at 0 -5.0292 0)
			(unlocked yes)
			(layer "F.Fab")
			(hide yes)
			(effects
				(font
					(size 2.54 2.54)
					(thickness 0.381)
				)
			)
		)
		(duplicate_pad_numbers_are_jumpers no)
		(fp_line
			(start 0.508 0)
			(end -0.508 0)
			(stroke
				(width 0.2032)
				(type default)
			)
			(layer "F.SilkS")
		)
		(fp_rect
			(start -0.5842 1.3335)
			(end 0.5842 -1.3335)
			(stroke
				(width 0)
				(type default)
			)
			(fill no)
			(layer "F.CrtYd")
		)
		(fp_rect
			(start -0.5842 1.3335)
			(end 0.5842 -1.3335)
			(stroke
				(width 0)
				(type default)
			)
			(fill no)
			(layer "F.Fab")
		)
		(pad "1" smd custom
			(at 0 -0.762)
			(size 0.2159 0.2159)
			(layers "F.Cu" "F.Mask" "F.Paste")
			(net "SYS_RESET_BTN_B")
			(options
				(clearance outline)
				(anchor circle)
			)
			(primitives
				(gr_poly
					(pts
						(arc
							(start -0.3302 -0.4318)
							(mid -0.402042 -0.402042)
							(end -0.4318 -0.3302)
						)
						(arc
							(start -0.4318 0.3302)
							(mid -0.402042 0.402042)
							(end -0.3302 0.4318)
						)
						(arc
							(start 0.3302 0.4318)
							(mid 0.402042 0.402042)
							(end 0.4318 0.3302)
						)
						(arc
							(start 0.4318 -0.3302)
							(mid 0.402042 -0.402042)
							(end 0.3302 -0.4318)
						)
					)
					(width 0)
					(fill yes)
				)
			)
		)
		(pad "2" smd custom
			(at 0 0.762)
			(size 0.2159 0.2159)
			(layers "F.Cu" "F.Mask" "F.Paste")
			(net "GND")
			(options
				(clearance outline)
				(anchor circle)
			)
			(primitives
				(gr_poly
					(pts
						(arc
							(start -0.3302 -0.4318)
							(mid -0.402042 -0.402042)
							(end -0.4318 -0.3302)
						)
						(arc
							(start -0.4318 0.3302)
							(mid -0.402042 0.402042)
							(end -0.3302 0.4318)
						)
						(arc
							(start 0.3302 0.4318)
							(mid 0.402042 0.402042)
							(end 0.4318 0.3302)
						)
						(arc
							(start 0.4318 -0.3302)
							(mid 0.402042 -0.402042)
							(end 0.3302 -0.4318)
						)
					)
					(width 0)
					(fill yes)
				)
			)
		)
	)
)
